FILE_TYPE = CONNECTIVITY;
{Allegro Design Entry HDL 17.2-2016 S081 (4005846) 1/11/2022}
"PAGE_NUMBER" = 78;
0"NC";
1"PVCCFA_EHV_CPU1\g";
2"PVCCFA_EHV_FIVRA_CPU1\g";
3"PVCCINFAON_CPU1\g";
4"PVCCD_HV_CPU1\g";
5"PVCCIN_CPU1\g";
6"PVCCIN_CPU1\g";
7"PVPP_HBM_CPU1\g";
8"PVNN_MAIN_CPU1\g";
9"PVCCIN_CPU1\g";
10"GND\g";
11"GND\g";
12"GND\g";
13"GND\g";
14"GND\g";
15"GND\g";
16"GND\g";
17"GND\g";
18"GND\g";
%"Q_CAP"
"1","(-4450,-2200)","0","pure_quanta","I1";
;
PART_NUMBER"CH647KMEA04"
TOLERANCE"20%"
VOLTAGE"4V"
PACK_TYPE"C0805"
VALUE"47UF"
MATERIAL"X6S"
$LOCATION"C449"
CDS_LIB"pure_quanta"
CDS_LOCATION"C449"
$SEC"1"
CDS_SEC"1";
"B"
$PN"2"10;
"A"
$PN"1"2;
%"Q_CAP"
"1","(-4450,-225)","0","pure_quanta","I10";
;
PART_NUMBER"CH647KMEA04"
TOLERANCE"20%"
VOLTAGE"4V"
PACK_TYPE"C0805"
VALUE"47UF"
MATERIAL"X6S"
$LOCATION"C448"
CDS_LIB"pure_quanta"
CDS_LOCATION"C448"
$SEC"1"
CDS_SEC"1";
"B"
$PN"2"11;
"A"
$PN"1"1;
%"UNIVERSAL_POWER"
"1","(-4450,50)","0","logical_power","I11";
;
HDL_POWER"PVCCFA_EHV_CPU1"
CDS_LIB"logical_power";
"A"1;
%"Q_CAP"
"1","(-4450,675)","0","pure_quanta","I12";
;
PART_NUMBER"CH647KMEA04"
TOLERANCE"20%"
VOLTAGE"4V"
VALUE"47UF"
MATERIAL"X6S"
PACK_TYPE"C0805"
$LOCATION"C447"
CDS_LIB"pure_quanta"
CDS_LOCATION"C447"
$SEC"1"
CDS_SEC"1";
"B"
$PN"2"13;
"A"
$PN"1"4;
%"UNIVERSAL_POWER"
"1","(-4450,950)","0","logical_power","I13";
;
HDL_POWER"PVCCD_HV_CPU1"
CDS_LIB"logical_power";
"A"4;
%"Q_CAP"
"1","(-4450,1625)","0","pure_quanta","I14";
;
PART_NUMBER"CH647KMEA04"
VALUE"47UF"
TOLERANCE"20%"
VOLTAGE"4V"
PACK_TYPE"C0805"
MATERIAL"X6S"
$LOCATION"C312"
CDS_LIB"pure_quanta"
$LOCATION"C312"
CDS_LOCATION"C312"
$SEC"1"
CDS_SEC"1";
"B"
$PN"2"16;
"A"
$PN"1"5;
%"UNIVERSAL_POWER"
"1","(-4450,1900)","0","logical_power","I15";
;
HDL_POWER"PVCCIN_CPU1"
CDS_LIB"logical_power";
"A"5;
%"Q_CAP"
"1","(-4450,2400)","0","pure_quanta","I16";
;
PART_NUMBER"CH647KMEA04"
TOLERANCE"20%"
VOLTAGE"4V"
PACK_TYPE"C0805"
VALUE"47UF"
MATERIAL"X6S"
$LOCATION"C311"
CDS_LIB"pure_quanta"
$LOCATION"C311"
CDS_LOCATION"C311"
$SEC"1"
CDS_SEC"1";
"B"
$PN"2"17;
"A"
$PN"1"6;
%"UNIVERSAL_POWER"
"1","(-4450,2675)","0","logical_power","I17";
;
HDL_POWER"PVCCIN_CPU1"
CDS_LIB"logical_power";
"A"6;
%"Q_CAP"
"1","(-4000,-1250)","0","pure_quanta","I18";
;
PART_NUMBER"CH647LME900"
TOLERANCE"20%"
VOLTAGE"2.5V"
MATERIAL"X6S"
PACK_TYPE"C0603"
VALUE"47UF"
$LOCATION"C488"
CDS_LIB"pure_quanta"
CDS_LOCATION"C488"
$SEC"1"
CDS_SEC"1";
"B"
$PN"2"12;
"A"
$PN"1"3;
%"Q_CAP"
"1","(-3550,-1250)","0","pure_quanta","I19";
;
PART_NUMBER"CH647LME900"
TOLERANCE"20%"
VOLTAGE"2.5V"
MATERIAL"X6S"
PACK_TYPE"C0603"
VALUE"47UF"
$LOCATION"C489"
CDS_LIB"pure_quanta"
CDS_LOCATION"C489"
$SEC"1"
CDS_SEC"1";
"B"
$PN"2"12;
"A"
$PN"1"3;
%"UNIVERSAL_POWER"
"1","(-4450,-1925)","0","logical_power","I2";
;
HDL_POWER"PVCCFA_EHV_FIVRA_CPU1"
CDS_LIB"logical_power";
"A"2;
%"UNIVERSAL_GND"
"1","(-4000,-575)","0","logical_power","I20";
;
CDS_LIB"logical_power"
HDL_POWER"GND";
"A"11;
%"Q_CAP"
"1","(-4000,-225)","0","pure_quanta","I21";
;
PART_NUMBER"CH647KMEA04"
TOLERANCE"20%"
VOLTAGE"4V"
PACK_TYPE"C0805"
VALUE"47UF"
MATERIAL"X6S"
$LOCATION"C452"
CDS_LIB"pure_quanta"
CDS_LOCATION"C452"
$SEC"1"
CDS_SEC"1";
"B"
$PN"2"11;
"A"
$PN"1"1;
%"UNIVERSAL_GND"
"1","(-3100,-1600)","0","logical_power","I22";
;
CDS_LIB"logical_power"
HDL_POWER"GND";
"A"12;
%"Q_CAP"
"1","(-3100,-1250)","0","pure_quanta","I23";
;
PART_NUMBER"CH622KMEB01"
VALUE"22UF"
TOLERANCE"20%"
MATERIAL"X6S"
VOLTAGE"4V"
PACK_TYPE"C0402"
$LOCATION"C490"
CDS_LIB"pure_quanta"
CDS_LOCATION"C490"
$SEC"1"
CDS_SEC"1";
"B"
$PN"2"12;
"A"
$PN"1"3;
%"Q_CAP"
"1","(-4000,675)","0","pure_quanta","I24";
;
PART_NUMBER"CH647KMEA04"
TOLERANCE"20%"
VOLTAGE"4V"
PACK_TYPE"C0805"
VALUE"47UF"
MATERIAL"X6S"
$LOCATION"C451"
CDS_LIB"pure_quanta"
CDS_LOCATION"C451"
$SEC"1"
CDS_SEC"1";
"B"
$PN"2"13;
"A"
$PN"1"4;
%"Q_CAP"
"1","(-3550,675)","0","pure_quanta","I25";
;
PART_NUMBER"CH647KMEA04"
TOLERANCE"20%"
VOLTAGE"4V"
PACK_TYPE"C0805"
VALUE"47UF"
MATERIAL"X6S"
$LOCATION"C471"
CDS_LIB"pure_quanta"
CDS_LOCATION"C471"
$SEC"1"
CDS_SEC"1";
"B"
$PN"2"13;
"A"
$PN"1"4;
%"Q_CAP"
"1","(-4000,1625)","0","pure_quanta","I26";
;
PART_NUMBER"CH647KMEA04"
VALUE"47UF"
TOLERANCE"20%"
VOLTAGE"4V"
PACK_TYPE"C0805"
MATERIAL"X6S"
$LOCATION"C315"
CDS_LIB"pure_quanta"
$LOCATION"C315"
CDS_LOCATION"C315"
$SEC"1"
CDS_SEC"1";
"B"
$PN"2"16;
"A"
$PN"1"5;
%"Q_CAP"
"1","(-3550,1625)","0","pure_quanta","I27";
;
PART_NUMBER"CH647KMEA04"
VALUE"47UF"
TOLERANCE"20%"
VOLTAGE"4V"
PACK_TYPE"C0805"
MATERIAL"X6S"
$LOCATION"C318"
CDS_LIB"pure_quanta"
$LOCATION"C318"
CDS_LOCATION"C318"
$SEC"1"
CDS_SEC"1";
"B"
$PN"2"16;
"A"
$PN"1"5;
%"UNIVERSAL_GND"
"1","(-3100,350)","0","logical_power","I28";
;
CDS_LIB"logical_power"
HDL_POWER"GND";
"A"13;
%"Q_CAP"
"1","(-3100,675)","0","pure_quanta","I29";
;
PART_NUMBER"CH647KMEA04"
TOLERANCE"20%"
VOLTAGE"4V"
PACK_TYPE"C0805"
VALUE"47UF"
MATERIAL"X6S"
$LOCATION"C474"
CDS_LIB"pure_quanta"
CDS_LOCATION"C474"
$SEC"1"
CDS_SEC"1";
"B"
$PN"2"13;
"A"
$PN"1"4;
%"Q_CAP"
"1","(-4000,-2200)","0","pure_quanta","I3";
;
PART_NUMBER"CH647KMEA04"
TOLERANCE"20%"
VOLTAGE"4V"
PACK_TYPE"C0805"
VALUE"47UF"
MATERIAL"X6S"
$LOCATION"C453"
CDS_LIB"pure_quanta"
CDS_LOCATION"C453"
$SEC"1"
CDS_SEC"1";
"B"
$PN"2"10;
"A"
$PN"1"2;
%"Q_CAP"
"1","(-3100,1625)","0","pure_quanta","I30";
;
PART_NUMBER"CH647KMEA04"
VALUE"47UF"
TOLERANCE"20%"
VOLTAGE"4V"
PACK_TYPE"C0805"
MATERIAL"X6S"
$LOCATION"C321"
CDS_LIB"pure_quanta"
$LOCATION"C321"
CDS_LOCATION"C321"
$SEC"1"
CDS_SEC"1";
"B"
$PN"2"16;
"A"
$PN"1"5;
%"Q_CAP"
"1","(-2650,1625)","0","pure_quanta","I31";
;
PART_NUMBER"CH647KMEA04"
VALUE"47UF"
TOLERANCE"20%"
VOLTAGE"4V"
PACK_TYPE"C0805"
MATERIAL"X6S"
$LOCATION"C324"
CDS_LIB"pure_quanta"
$LOCATION"C324"
CDS_LOCATION"C324"
$SEC"1"
CDS_SEC"1";
"B"
$PN"2"16;
"A"
$PN"1"5;
%"Q_CAP"
"1","(-2200,1625)","0","pure_quanta","I32";
;
PART_NUMBER"CH647KMEA04"
VALUE"47UF"
TOLERANCE"20%"
VOLTAGE"4V"
PACK_TYPE"C0805"
MATERIAL"X6S"
$LOCATION"C327"
CDS_LIB"pure_quanta"
$LOCATION"C327"
CDS_LOCATION"C327"
$SEC"1"
CDS_SEC"1";
"B"
$PN"2"16;
"A"
$PN"1"5;
%"Q_CAP"
"1","(-1750,1625)","0","pure_quanta","I33";
;
PART_NUMBER"CH647KMEA04"
VALUE"47UF"
TOLERANCE"20%"
VOLTAGE"4V"
PACK_TYPE"C0805"
MATERIAL"X6S"
$LOCATION"C330"
CDS_LIB"pure_quanta"
$LOCATION"C330"
CDS_LOCATION"C330"
$SEC"1"
CDS_SEC"1";
"B"
$PN"2"16;
"A"
$PN"1"5;
%"Q_CAP"
"1","(-1300,1625)","0","pure_quanta","I34";
;
PART_NUMBER"CH647KMEA04"
TOLERANCE"20%"
VALUE"47UF"
VOLTAGE"4V"
PACK_TYPE"C0805"
MATERIAL"X6S"
$LOCATION"C333"
CDS_LIB"pure_quanta"
$LOCATION"C333"
CDS_LOCATION"C333"
$SEC"1"
CDS_SEC"1";
"B"
$PN"2"16;
"A"
$PN"1"5;
%"Q_CAP"
"1","(-850,1625)","0","pure_quanta","I35";
;
PART_NUMBER"CH647KMEA04"
VALUE"47UF"
TOLERANCE"20%"
VOLTAGE"4V"
PACK_TYPE"C0805"
MATERIAL"X6S"
$LOCATION"C336"
CDS_LIB"pure_quanta"
$LOCATION"C336"
CDS_LOCATION"C336"
$SEC"1"
CDS_SEC"1";
"B"
$PN"2"16;
"A"
$PN"1"5;
%"Q_CAP"
"1","(-400,1625)","0","pure_quanta","I36";
;
PART_NUMBER"CH647KMEA04"
VALUE"47UF"
TOLERANCE"20%"
VOLTAGE"4V"
PACK_TYPE"C0805"
MATERIAL"X6S"
$LOCATION"C339"
CDS_LIB"pure_quanta"
$LOCATION"C339"
CDS_LOCATION"C339"
$SEC"1"
CDS_SEC"1";
"B"
$PN"2"16;
"A"
$PN"1"5;
%"Q_CAP"
"1","(-4000,2400)","0","pure_quanta","I37";
;
PART_NUMBER"CH647KMEA04"
TOLERANCE"20%"
VOLTAGE"4V"
PACK_TYPE"C0805"
VALUE"47UF"
MATERIAL"X6S"
$LOCATION"C314"
CDS_LIB"pure_quanta"
$LOCATION"C314"
CDS_LOCATION"C314"
$SEC"1"
CDS_SEC"1";
"B"
$PN"2"17;
"A"
$PN"1"6;
%"Q_CAP"
"1","(-3550,2400)","0","pure_quanta","I38";
;
PART_NUMBER"CH647KMEA04"
TOLERANCE"20%"
VOLTAGE"4V"
PACK_TYPE"C0805"
VALUE"47UF"
MATERIAL"X6S"
$LOCATION"C317"
CDS_LIB"pure_quanta"
$LOCATION"C317"
CDS_LOCATION"C317"
$SEC"1"
CDS_SEC"1";
"B"
$PN"2"17;
"A"
$PN"1"6;
%"Q_CAP"
"1","(-3100,2400)","0","pure_quanta","I39";
;
PART_NUMBER"CH647KMEA04"
TOLERANCE"20%"
VOLTAGE"4V"
PACK_TYPE"C0805"
VALUE"47UF"
MATERIAL"X6S"
$LOCATION"C320"
CDS_LIB"pure_quanta"
$LOCATION"C320"
CDS_LOCATION"C320"
$SEC"1"
CDS_SEC"1";
"B"
$PN"2"17;
"A"
$PN"1"6;
%"Q_CAP"
"1","(-3550,-2200)","0","pure_quanta","I4";
;
PART_NUMBER"CH647KMEA04"
TOLERANCE"20%"
VOLTAGE"4V"
PACK_TYPE"C0805"
VALUE"47UF"
MATERIAL"X6S"
$LOCATION"C457"
CDS_LIB"pure_quanta"
CDS_LOCATION"C457"
$SEC"1"
CDS_SEC"1";
"B"
$PN"2"10;
"A"
$PN"1"2;
%"Q_CAP"
"1","(-2650,2400)","0","pure_quanta","I40";
;
PART_NUMBER"CH647KMEA04"
TOLERANCE"20%"
VOLTAGE"4V"
PACK_TYPE"C0805"
VALUE"47UF"
MATERIAL"X6S"
$LOCATION"C323"
CDS_LIB"pure_quanta"
$LOCATION"C323"
CDS_LOCATION"C323"
$SEC"1"
CDS_SEC"1";
"B"
$PN"2"17;
"A"
$PN"1"6;
%"Q_CAP"
"1","(-2200,2400)","0","pure_quanta","I41";
;
PART_NUMBER"CH647KMEA04"
TOLERANCE"20%"
VOLTAGE"4V"
PACK_TYPE"C0805"
VALUE"47UF"
MATERIAL"X6S"
$LOCATION"C326"
CDS_LIB"pure_quanta"
$LOCATION"C326"
CDS_LOCATION"C326"
$SEC"1"
CDS_SEC"1";
"B"
$PN"2"17;
"A"
$PN"1"6;
%"Q_CAP"
"1","(-1750,2400)","0","pure_quanta","I42";
;
PART_NUMBER"CH647KMEA04"
TOLERANCE"20%"
VOLTAGE"4V"
PACK_TYPE"C0805"
VALUE"47UF"
MATERIAL"X6S"
$LOCATION"C329"
CDS_LIB"pure_quanta"
$LOCATION"C329"
CDS_LOCATION"C329"
$SEC"1"
CDS_SEC"1";
"B"
$PN"2"17;
"A"
$PN"1"6;
%"Q_CAP"
"1","(-1300,2400)","0","pure_quanta","I43";
;
PART_NUMBER"CH647KMEA04"
TOLERANCE"20%"
VOLTAGE"4V"
PACK_TYPE"C0805"
VALUE"47UF"
MATERIAL"X6S"
$LOCATION"C332"
CDS_LIB"pure_quanta"
$LOCATION"C332"
CDS_LOCATION"C332"
$SEC"1"
CDS_SEC"1";
"B"
$PN"2"17;
"A"
$PN"1"6;
%"Q_CAP"
"1","(-850,2400)","0","pure_quanta","I44";
;
PART_NUMBER"CH647KMEA04"
TOLERANCE"20%"
VOLTAGE"4V"
PACK_TYPE"C0805"
VALUE"47UF"
MATERIAL"X6S"
$LOCATION"C335"
CDS_LIB"pure_quanta"
$LOCATION"C335"
CDS_LOCATION"C335"
$SEC"1"
CDS_SEC"1";
"B"
$PN"2"17;
"A"
$PN"1"6;
%"Q_CAP"
"1","(-400,2400)","0","pure_quanta","I45";
;
PART_NUMBER"CH647KMEA04"
TOLERANCE"20%"
VOLTAGE"4V"
PACK_TYPE"C0805"
VALUE"47UF"
MATERIAL"X6S"
$LOCATION"C338"
CDS_LIB"pure_quanta"
$LOCATION"C338"
CDS_LOCATION"C338"
$SEC"1"
CDS_SEC"1";
"B"
$PN"2"17;
"A"
$PN"1"6;
%"Q_CAP"
"1","(-100,-1250)","0","pure_quanta","I46";
;
PART_NUMBER"CH647KMEA04"
PACK_TYPE"C0805"
VALUE"47UF"
MATERIAL"X6S"
VOLTAGE"4V"
TOLERANCE"20%"
$LOCATION"C1388"
CDS_LIB"pure_quanta"
CDS_LOCATION"C1388"
$SEC"1"
CDS_SEC"1";
"B"
$PN"2"14;
"A"
$PN"1"7;
%"UNIVERSAL_POWER"
"1","(-100,-975)","0","logical_power","I47";
;
HDL_POWER"PVPP_HBM_CPU1"
CDS_LIB"logical_power";
"A"7;
%"Q_CAP"
"1","(350,-1250)","0","pure_quanta","I48";
;
PART_NUMBER"CH647KMEA04"
VALUE"47UF"
TOLERANCE"20%"
MATERIAL"X6S"
VOLTAGE"4V"
PACK_TYPE"C0805"
$LOCATION"C1390"
CDS_LIB"pure_quanta"
CDS_LOCATION"C1390"
$SEC"1"
CDS_SEC"1";
"B"
$PN"2"14;
"A"
$PN"1"7;
%"Q_CAP"
"1","(-100,-225)","0","pure_quanta","I49";
;
PART_NUMBER"CH647KMEA04"
PACK_TYPE"C0805"
VALUE"47UF"
TOLERANCE"20%"
MATERIAL"X6S"
VOLTAGE"4V"
$LOCATION"C1387"
CDS_LIB"pure_quanta"
CDS_LOCATION"C1387"
$SEC"1"
CDS_SEC"1";
"B"
$PN"2"15;
"A"
$PN"1"8;
%"Q_CAP"
"1","(-3100,-2200)","0","pure_quanta","I5";
;
PART_NUMBER"CH647KMEA04"
VALUE"47UF"
MATERIAL"X6S"
VOLTAGE"4V"
TOLERANCE"20%"
PACK_TYPE"C0805"
$LOCATION"C461"
CDS_LIB"pure_quanta"
CDS_LOCATION"C461"
$SEC"1"
CDS_SEC"1";
"B"
$PN"2"10;
"A"
$PN"1"2;
%"UNIVERSAL_POWER"
"1","(-100,50)","0","logical_power","I50";
;
HDL_POWER"PVNN_MAIN_CPU1"
CDS_LIB"logical_power";
"A"8;
%"Q_CAP"
"1","(350,-225)","0","pure_quanta","I51";
;
PART_NUMBER"CH647LME900"
TOLERANCE"20%"
MATERIAL"X6S"
PACK_TYPE"C0603"
VOLTAGE"2.5V"
VALUE"47UF"
$LOCATION"C1389"
CDS_LIB"pure_quanta"
CDS_LOCATION"C1389"
$SEC"1"
CDS_SEC"1";
"B"
$PN"2"15;
"A"
$PN"1"8;
%"Q_CAP"
"1","(800,-225)","0","pure_quanta","I52";
;
PART_NUMBER"CH647LME900"
TOLERANCE"20%"
MATERIAL"X6S"
VALUE"47UF"
VOLTAGE"2.5V"
PACK_TYPE"C0603"
$LOCATION"C1391"
CDS_LIB"pure_quanta"
CDS_LOCATION"C1391"
$SEC"1"
CDS_SEC"1";
"B"
$PN"2"15;
"A"
$PN"1"8;
%"Q_CAP"
"1","(800,-1250)","0","pure_quanta","I53";
;
PART_NUMBER"CH647KMEA04"
PACK_TYPE"C0805"
VALUE"47UF"
TOLERANCE"20%"
MATERIAL"X6S"
VOLTAGE"4V"
$LOCATION"C1392"
CDS_LIB"pure_quanta"
CDS_LOCATION"C1392"
$SEC"1"
CDS_SEC"1";
"B"
$PN"2"14;
"A"
$PN"1"7;
%"UNIVERSAL_GND"
"1","(1250,-1600)","0","logical_power","I54";
;
CDS_LIB"logical_power"
HDL_POWER"GND";
"A"14;
%"Q_CAP"
"1","(1250,-1250)","0","pure_quanta","I55";
;
PART_NUMBER"CH4221KEE00"
MATERIAL"X6S"
VALUE"0.22UF"
PACK_TYPE"C0201"
TOLERANCE"10%"
VOLTAGE"6.3V"
$LOCATION"C1437"
CDS_LIB"pure_quanta"
CDS_LOCATION"C1437"
$SEC"1"
CDS_SEC"1";
"B"
$PN"2"14;
"A"
$PN"1"7;
%"UNIVERSAL_GND"
"1","(1250,-575)","0","logical_power","I56";
;
CDS_LIB"logical_power"
HDL_POWER"GND";
"A"15;
%"Q_CAP"
"1","(1250,-225)","0","pure_quanta","I57";
;
PART_NUMBER"CH647LME900"
TOLERANCE"20%"
MATERIAL"X6S"
VALUE"47UF"
VOLTAGE"2.5V"
PACK_TYPE"C0603"
$LOCATION"C1393"
CDS_LIB"pure_quanta"
CDS_LOCATION"C1393"
$SEC"1"
CDS_SEC"1";
"B"
$PN"2"15;
"A"
$PN"1"8;
%"Q_CAP"
"1","(50,1625)","0","pure_quanta","I58";
;
PART_NUMBER"CH647KMEA04"
VOLTAGE"4V"
VALUE"47UF"
TOLERANCE"20%"
PACK_TYPE"C0805"
MATERIAL"X6S"
$LOCATION"C313"
CDS_LIB"pure_quanta"
$LOCATION"C313"
CDS_LOCATION"C313"
$SEC"1"
CDS_SEC"1";
"B"
$PN"2"16;
"A"
$PN"1"5;
%"UNIVERSAL_GND"
"1","(500,1275)","0","logical_power","I59";
;
CDS_LIB"logical_power"
HDL_POWER"GND";
"A"16;
%"UNIVERSAL_GND"
"1","(-2650,-2550)","0","logical_power","I6";
;
CDS_LIB"logical_power"
HDL_POWER"GND";
"A"10;
%"Q_CAP"
"1","(500,1625)","0","pure_quanta","I60";
;
PART_NUMBER"CH647KMEA04"
TOLERANCE"20%"
VALUE"47UF"
VOLTAGE"4V"
PACK_TYPE"C0805"
MATERIAL"X6S"
$LOCATION"C316"
CDS_LIB"pure_quanta"
$LOCATION"C316"
CDS_LOCATION"C316"
$SEC"1"
CDS_SEC"1";
"B"
$PN"2"16;
"A"
$PN"1"5;
%"UNIVERSAL_GND"
"1","(950,2050)","0","logical_power","I61";
;
CDS_LIB"logical_power"
HDL_POWER"GND";
"A"17;
%"UNIVERSAL_GND"
"1","(2275,2050)","0","logical_power","I62";
;
CDS_LIB"logical_power"
HDL_POWER"GND";
"A"18;
%"Q_CAP"
"1","(50,2400)","0","pure_quanta","I63";
;
PART_NUMBER"CH647KMEA04"
TOLERANCE"20%"
VOLTAGE"4V"
PACK_TYPE"C0805"
VALUE"47UF"
MATERIAL"X6S"
$LOCATION"C349"
CDS_LIB"pure_quanta"
$LOCATION"C349"
CDS_LOCATION"C349"
$SEC"1"
CDS_SEC"1";
"B"
$PN"2"17;
"A"
$PN"1"6;
%"Q_CAP"
"1","(500,2400)","0","pure_quanta","I64";
;
PART_NUMBER"CH647KMEA04"
TOLERANCE"20%"
VOLTAGE"4V"
PACK_TYPE"C0805"
VALUE"47UF"
MATERIAL"X6S"
$LOCATION"C351"
CDS_LIB"pure_quanta"
$LOCATION"C351"
CDS_LOCATION"C351"
$SEC"1"
CDS_SEC"1";
"B"
$PN"2"17;
"A"
$PN"1"6;
%"Q_CAP"
"1","(950,2400)","0","pure_quanta","I65";
;
PART_NUMBER"CH647KMEA04"
TOLERANCE"20%"
VOLTAGE"4V"
PACK_TYPE"C0805"
VALUE"47UF"
MATERIAL"X6S"
$LOCATION"C353"
CDS_LIB"pure_quanta"
$LOCATION"C353"
CDS_LOCATION"C353"
$SEC"1"
CDS_SEC"1";
"B"
$PN"2"17;
"A"
$PN"1"6;
%"Q_CAP"
"1","(1825,2400)","0","pure_quanta","I66";
;
PART_NUMBER"CH647KMEA04"
VALUE"47UF"
VOLTAGE"4V"
PACK_TYPE"C0805"
TOLERANCE"20%"
MATERIAL"X6S"
$LOCATION"C337"
CDS_LIB"pure_quanta"
CDS_LOCATION"C337"
$SEC"1"
CDS_SEC"1";
"B"
$PN"2"18;
"A"
$PN"1"9;
%"UNIVERSAL_POWER"
"1","(1825,2675)","0","logical_power","I67";
;
HDL_POWER"PVCCIN_CPU1"
CDS_LIB"logical_power";
"A"9;
%"Q_CAP"
"1","(2275,2400)","0","pure_quanta","I68";
;
PART_NUMBER"CH647KMEA04"
VOLTAGE"4V"
VALUE"47UF"
PACK_TYPE"C0805"
MATERIAL"X6S"
TOLERANCE"20%"
$LOCATION"C483"
CDS_LIB"pure_quanta"
CDS_LOCATION"C483"
$SEC"1"
CDS_SEC"1";
"B"
$PN"2"18;
"A"
$PN"1"9;
%"Q_CAP"
"1","(-2650,-2200)","0","pure_quanta","I7";
;
PART_NUMBER"CH647LME900"
TOLERANCE"20%"
MATERIAL"X6S"
VOLTAGE"2.5V"
PACK_TYPE"C0603"
VALUE"47UF"
$LOCATION"C465"
CDS_LIB"pure_quanta"
CDS_LOCATION"C465"
$SEC"1"
CDS_SEC"1";
"B"
$PN"2"10;
"A"
$PN"1"2;
%"Q_CAP"
"1","(-4450,-1250)","0","pure_quanta","I8";
;
PART_NUMBER"CH647KMEA04"
PACK_TYPE"C0805"
VALUE"47UF"
TOLERANCE"20%"
MATERIAL"X6S"
VOLTAGE"4V"
$LOCATION"C478"
CDS_LIB"pure_quanta"
CDS_LOCATION"C478"
$SEC"1"
CDS_SEC"1";
"B"
$PN"2"12;
"A"
$PN"1"3;
%"UNIVERSAL_POWER"
"1","(-4450,-975)","0","logical_power","I9";
;
HDL_POWER"PVCCINFAON_CPU1"
CDS_LIB"logical_power";
"A"3;
END.
